# BASEBOARD_FAB2 (Tioga Pass) — schematic netlist excerpt (pin names and nets, part order shuffled) for the footprints in the layout excerpt that follows; sources: Cadence DE-HDL packaged netlist, KiCad conversion of Wiwynn_Tioga_Pass_MB.brd

CTI7  CAP  1000PF 50V 10% X7R  pkg 0402LF  page 208 : A = A_TSENSE_PVCCIN_CPU1 ; B = GND
R3P21  RES  100.0K 1% EMPTY  pkg 0402  page 211 : A = P3V3_STBY ; B = VR_PVCCIO_CPU0_EN
C9L7  CAP_A  0.01UF 25V 10% X7R  pkg 0402V  page 85 : A = M_L_VREF ; B = GND

(kicad_pcb
	(version 20260206)
	(generator "pcbnew")
	(generator_version "10.0")
	(general
		(thickness 1.6)
		(legacy_teardrops no)
	)
	(paper "A4")
	(title_block
		(title "Wiwynn_Tioga_Pass_MB.brd")
		(comment 1 "Tioga Pass / footprints 2952-2954 of 4770")
	)
	(layers
		(0 "F.Cu" signal "TOP")
		(4 "In1.Cu" signal "L2GND")
		(6 "In2.Cu" signal "L3")
		(8 "In3.Cu" signal "L4GND")
		(10 "In4.Cu" signal "L5")
		(12 "In5.Cu" signal "L6GND")
		(14 "In6.Cu" signal "L7VCC")
		(16 "In7.Cu" signal "L8VCC")
		(18 "In8.Cu" signal "L9GND")
		(20 "In9.Cu" signal "L10")
		(22 "In10.Cu" signal "L11GND")
		(24 "In11.Cu" signal "L12")
		(26 "In12.Cu" signal "L13GND")
		(2 "B.Cu" signal "BOTTOM")
		(9 "F.Adhes" user "F.Adhesive")
		(11 "B.Adhes" user "B.Adhesive")
		(13 "F.Paste" user "Package Geometry/Pastemask Top")
		(15 "B.Paste" user "Package Geometry/Pastemask Bottom")
		(5 "F.SilkS" user "Ref Des/Silkscreen Top")
		(7 "B.SilkS" user "Ref Des/Silkscreen Bottom")
		(1 "F.Mask" user "Board Geometry/Soldermask Top")
		(3 "B.Mask" user "Board Geometry/Soldermask Bottom")
		(17 "Dwgs.User" user "User.Drawings")
		(19 "Cmts.User" user "User.Comments")
		(21 "Eco1.User" user "User.Eco1")
		(23 "Eco2.User" user "User.Eco2")
		(25 "Edge.Cuts" user "Board Geometry/Outline")
		(27 "Margin" user)
		(31 "F.CrtYd" user "Package Geometry/Place Bound Top")
		(29 "B.CrtYd" user "Package Geometry/Place Bound Bottom")
		(35 "F.Fab" user "Ref Des/Assembly Top")
		(33 "B.Fab" user "Ref Des/Assembly Bottom")
	)
	(footprint ""
		(layer "B.Cu")
		(at 340.741 -83.5914 90)
		(property "Reference" "R3P21"
			(at 0 0 90)
			(layer "B.SilkS")
			(hide yes)
			(effects
				(font
					(size 1.27 1.27)
				)
				(justify mirror)
			)
		)
		(property "Value" ""
			(at 0 0 90)
			(layer "B.Fab")
			(effects
				(font
					(size 1.27 1.27)
				)
				(justify mirror)
			)
		)
		(duplicate_pad_numbers_are_jumpers no)
		(fp_poly
			(pts
				(xy 0.2794 -0.1016) (xy -0.2794 -0.1016) (xy -0.2794 0.9906) (xy 0.2794 0.9906)
			)
			(stroke
				(width 0)
				(type default)
			)
			(fill no)
			(layer "B.CrtYd")
		)
		(fp_line
			(start 0.2794 -0.1016)
			(end 0.2794 0.9906)
			(stroke
				(width 0.1)
				(type default)
			)
			(layer "B.Fab")
		)
		(fp_line
			(start -0.2794 -0.1016)
			(end 0.2794 -0.1016)
			(stroke
				(width 0.1)
				(type default)
			)
			(layer "B.Fab")
		)
		(fp_line
			(start 0.2794 0.9906)
			(end -0.2794 0.9906)
			(stroke
				(width 0.1)
				(type default)
			)
			(layer "B.Fab")
		)
		(fp_line
			(start -0.2794 0.9906)
			(end -0.2794 -0.1016)
			(stroke
				(width 0.1)
				(type default)
			)
			(layer "B.Fab")
		)
		(pad "1" smd rect
			(at 0 0 270)
			(size 0.508 0.508)
			(layers "B.Cu" "B.Mask" "B.Paste")
			(net "P3V3_STBY")
		)
		(pad "2" smd rect
			(at 0 0.889 270)
			(size 0.508 0.508)
			(layers "B.Cu" "B.Mask" "B.Paste")
			(net "VR_PVCCIO_CPU0_EN")
		)
		(zone
			(layer "B.Cu")
			(hatch none 0.5)
			(connect_pads
				(clearance 0)
			)
			(min_thickness 0.25)
			(keepout
				(tracks allowed)
				(vias not_allowed)
				(pads allowed)
				(copperpour not_allowed)
				(footprints allowed)
			)
			(placement
				(enabled no)
				(sheetname "")
			)
			(fill
				(thermal_gap 0.5)
				(thermal_bridge_width 0.5)
				(island_removal_mode 0)
			)
			(polygon
				(pts
					(xy 340.995 -83.8454) (xy 340.995 -83.3374) (xy 341.376 -83.3374) (xy 341.376 -83.8454)
				)
			)
		)
		(zone
			(layer "B.Cu")
			(hatch none 0.5)
			(connect_pads
				(clearance 0)
			)
			(min_thickness 0.25)
			(keepout
				(tracks not_allowed)
				(vias allowed)
				(pads allowed)
				(copperpour not_allowed)
				(footprints allowed)
			)
			(placement
				(enabled no)
				(sheetname "")
			)
			(fill
				(thermal_gap 0.5)
				(thermal_bridge_width 0.5)
				(island_removal_mode 0)
			)
			(polygon
				(pts
					(xy 341.376 -83.8454) (xy 341.376 -83.3374) (xy 340.995 -83.3374) (xy 340.995 -83.8454)
				)
			)
		)
	)
	(footprint ""
		(layer "B.Cu")
		(at 31.0134 -72.1614 180)
		(property "Reference" "CTI7"
			(at 0.8382 -0.84963 180)
			(unlocked yes)
			(layer "B.SilkS")
			(effects
				(font
					(size 0.7874 0.5842)
					(thickness 0.1524)
				)
				(justify left mirror)
			)
		)
		(property "Value" ""
			(at 0 0 0)
			(layer "B.Fab")
			(effects
				(font
					(size 1.27 1.27)
				)
				(justify mirror)
			)
		)
		(duplicate_pad_numbers_are_jumpers no)
		(fp_poly
			(pts
				(xy -0.3048 -0.1016) (xy -0.3048 0.9906) (xy 0.3048 0.9906) (xy 0.3048 -0.1016)
			)
			(stroke
				(width 0)
				(type default)
			)
			(fill no)
			(layer "B.CrtYd")
		)
		(fp_line
			(start 0.3048 0.9906)
			(end -0.3048 0.9906)
			(stroke
				(width 0.1)
				(type default)
			)
			(layer "B.Fab")
		)
		(fp_line
			(start 0.3048 -0.1016)
			(end 0.3048 0.9906)
			(stroke
				(width 0.1)
				(type default)
			)
			(layer "B.Fab")
		)
		(fp_line
			(start -0.3048 0.9906)
			(end -0.3048 -0.1016)
			(stroke
				(width 0.1)
				(type default)
			)
			(layer "B.Fab")
		)
		(fp_line
			(start -0.3048 -0.1016)
			(end 0.3048 -0.1016)
			(stroke
				(width 0.1)
				(type default)
			)
			(layer "B.Fab")
		)
		(pad "1" smd rect
			(at 0 0)
			(size 0.508 0.508)
			(layers "B.Cu" "B.Mask" "B.Paste")
			(net "A_TSENSE_PVCCIN_CPU1")
		)
		(pad "2" smd rect
			(at 0 0.889)
			(size 0.508 0.508)
			(layers "B.Cu" "B.Mask" "B.Paste")
			(net "GND")
		)
		(zone
			(layer "B.Cu")
			(hatch none 0.5)
			(connect_pads
				(clearance 0)
			)
			(min_thickness 0.25)
			(keepout
				(tracks not_allowed)
				(vias allowed)
				(pads allowed)
				(copperpour not_allowed)
				(footprints allowed)
			)
			(placement
				(enabled no)
				(sheetname "")
			)
			(fill
				(thermal_gap 0.5)
				(thermal_bridge_width 0.5)
				(island_removal_mode 0)
			)
			(polygon
				(pts
					(xy 30.7594 -72.7964) (xy 31.2674 -72.7964) (xy 31.2674 -72.4154) (xy 30.7594 -72.4154)
				)
			)
		)
		(zone
			(layer "B.Cu")
			(hatch none 0.5)
			(connect_pads
				(clearance 0)
			)
			(min_thickness 0.25)
			(keepout
				(tracks allowed)
				(vias not_allowed)
				(pads allowed)
				(copperpour not_allowed)
				(footprints allowed)
			)
			(placement
				(enabled no)
				(sheetname "")
			)
			(fill
				(thermal_gap 0.5)
				(thermal_bridge_width 0.5)
				(island_removal_mode 0)
			)
			(polygon
				(pts
					(xy 30.7594 -72.4154) (xy 31.2674 -72.4154) (xy 31.2674 -72.7964) (xy 30.7594 -72.7964)
				)
			)
		)
	)
	(footprint ""
		(layer "B.Cu")
		(at 30.452568 -144.977612 90)
		(property "Reference" "C9L7"
			(at 0 0 90)
			(layer "B.SilkS")
			(hide yes)
			(effects
				(font
					(size 1.27 1.27)
				)
				(justify mirror)
			)
		)
		(property "Value" ""
			(at 0 0 90)
			(layer "B.Fab")
			(effects
				(font
					(size 1.27 1.27)
				)
				(justify mirror)
			)
		)
		(duplicate_pad_numbers_are_jumpers no)
		(fp_poly
			(pts
				(xy -0.3048 -0.1016) (xy -0.3048 0.9906) (xy 0.3048 0.9906) (xy 0.3048 -0.1016)
			)
			(stroke
				(width 0)
				(type default)
			)
			(fill no)
			(layer "B.CrtYd")
		)
		(fp_line
			(start 0.3048 -0.1016)
			(end 0.3048 0.9906)
			(stroke
				(width 0.1)
				(type default)
			)
			(layer "B.Fab")
		)
		(fp_line
			(start -0.3048 -0.1016)
			(end 0.3048 -0.1016)
			(stroke
				(width 0.1)
				(type default)
			)
			(layer "B.Fab")
		)
		(fp_line
			(start 0.3048 0.9906)
			(end -0.3048 0.9906)
			(stroke
				(width 0.1)
				(type default)
			)
			(layer "B.Fab")
		)
		(fp_line
			(start -0.3048 0.9906)
			(end -0.3048 -0.1016)
			(stroke
				(width 0.1)
				(type default)
			)
			(layer "B.Fab")
		)
		(pad "1" smd rect
			(at 0 0 270)
			(size 0.508 0.508)
			(layers "B.Cu" "B.Mask" "B.Paste")
			(net "M_L_VREF")
		)
		(pad "2" smd rect
			(at 0 0.889 270)
			(size 0.508 0.508)
			(layers "B.Cu" "B.Mask" "B.Paste")
			(net "GND")
		)
		(zone
			(layer "B.Cu")
			(hatch none 0.5)
			(connect_pads
				(clearance 0)
			)
			(min_thickness 0.25)
			(keepout
				(tracks allowed)
				(vias not_allowed)
				(pads allowed)
				(copperpour not_allowed)
				(footprints allowed)
			)
			(placement
				(enabled no)
				(sheetname "")
			)
			(fill
				(thermal_gap 0.5)
				(thermal_bridge_width 0.5)
				(island_removal_mode 0)
			)
			(polygon
				(pts
					(xy 30.706568 -145.231612) (xy 30.706568 -144.723612) (xy 31.087568 -144.723612) (xy 31.087568 -145.231612)
				)
			)
		)
		(zone
			(layer "B.Cu")
			(hatch none 0.5)
			(connect_pads
				(clearance 0)
			)
			(min_thickness 0.25)
			(keepout
				(tracks not_allowed)
				(vias allowed)
				(pads allowed)
				(copperpour not_allowed)
				(footprints allowed)
			)
			(placement
				(enabled no)
				(sheetname "")
			)
			(fill
				(thermal_gap 0.5)
				(thermal_bridge_width 0.5)
				(island_removal_mode 0)
			)
			(polygon
				(pts
					(xy 31.087568 -145.231612) (xy 31.087568 -144.723612) (xy 30.706568 -144.723612) (xy 30.706568 -145.231612)
				)
			)
		)
	)
)
